# T6G (Grand Teton) — schematic netlist excerpt (pin names and nets, part order shuffled) for the footprints in the layout excerpt that follows; sources: Cadence DE-HDL packaged netlist, KiCad conversion of 04192023_DAF0TMB3IC0_F0TG_MB_C_brd_V02_OCP.brd

C63  Q_CAP  220PF 50V 5% C0G  pkg C0402  page 151 : A = UART_CPU0_SCM_LVC3_UART1_R_RX ; B = GND
R947  Q_RES  4.7K 5% CHIP  pkg 0402LF  page 166 : A = P3V3_AUX ; B = SMERR_LED
C870  Q_CAP_DIFFBUS  DIFF BUS_0.22UF 6.3V 20% X6S  pkg C0201  page 64 : \1\ = P5E_CPU0_P3_TX_C_DN<15> ; \2\ = P5E_CPU0_P3_TX_DN<15>

(kicad_pcb
	(version 20260206)
	(generator "pcbnew")
	(generator_version "10.0")
	(general
		(thickness 1.6)
		(legacy_teardrops no)
	)
	(paper "A4")
	(title_block
		(title "04192023_DAF0TMB3IC0_F0TG_MB_C_brd_V02_OCP.brd")
		(comment 1 "Grand Teton / footprints 1029-1031 of 8354")
	)
	(layers
		(0 "F.Cu" signal "TOP")
		(4 "In1.Cu" signal "GND")
		(6 "In2.Cu" signal "IN1")
		(8 "In3.Cu" signal "GND1")
		(10 "In4.Cu" signal "IN2")
		(12 "In5.Cu" signal "GND2")
		(14 "In6.Cu" signal "IN3")
		(16 "In7.Cu" signal "GND3")
		(18 "In8.Cu" signal "VCC")
		(20 "In9.Cu" signal "VCC1")
		(22 "In10.Cu" signal "GND4")
		(24 "In11.Cu" signal "IN4")
		(26 "In12.Cu" signal "GND5")
		(28 "In13.Cu" signal "IN5")
		(30 "In14.Cu" signal "GND6")
		(32 "In15.Cu" signal "IN6")
		(34 "In16.Cu" signal "GND7")
		(2 "B.Cu" signal "BOTTOM")
		(9 "F.Adhes" user "F.Adhesive")
		(11 "B.Adhes" user "B.Adhesive")
		(13 "F.Paste" user "Package Geometry/Pastemask Top")
		(15 "B.Paste" user "Package Geometry/Pastemask Bottom")
		(5 "F.SilkS" user "Ref Des/Silkscreen Top")
		(7 "B.SilkS" user "Ref Des/Silkscreen Bottom")
		(1 "F.Mask" user "Board Geometry/Soldermask Top")
		(3 "B.Mask" user "Board Geometry/Soldermask Bottom")
		(17 "Dwgs.User" user "User.Drawings")
		(19 "Cmts.User" user "User.Comments")
		(21 "Eco1.User" user "User.Eco1")
		(23 "Eco2.User" user "User.Eco2")
		(25 "Edge.Cuts" user "Board Geometry/Outline")
		(27 "Margin" user)
		(31 "F.CrtYd" user "Package Geometry/Place Bound Top")
		(29 "B.CrtYd" user "Package Geometry/Place Bound Bottom")
		(35 "F.Fab" user "Ref Des/Assembly Top")
		(33 "B.Fab" user "Ref Des/Assembly Bottom")
	)
	(footprint ""
		(layer "F.Cu")
		(at 392.840972 -388.767828)
		(property "Reference" "C870"
			(at 0 0 0)
			(layer "F.SilkS")
			(hide yes)
			(effects
				(font
					(size 1.27 1.27)
				)
			)
		)
		(property "Value" ""
			(at 0 0 0)
			(layer "F.Fab")
			(effects
				(font
					(size 1.27 1.27)
				)
			)
		)
		(duplicate_pad_numbers_are_jumpers no)
		(fp_line
			(start -0.299974 -0.150114)
			(end 0.299974 -0.150114)
			(stroke
				(width 0.1)
				(type default)
			)
			(layer "F.Fab")
		)
		(fp_line
			(start -0.299974 0.150114)
			(end -0.299974 -0.150114)
			(stroke
				(width 0.1)
				(type default)
			)
			(layer "F.Fab")
		)
		(fp_line
			(start 0.299974 -0.150114)
			(end 0.299974 0.150114)
			(stroke
				(width 0.1)
				(type default)
			)
			(layer "F.Fab")
		)
		(fp_line
			(start 0.299974 0.150114)
			(end -0.299974 0.150114)
			(stroke
				(width 0.1)
				(type default)
			)
			(layer "F.Fab")
		)
		(pad "1" smd rect
			(at -0.2667 0)
			(size 0.3048 0.381)
			(layers "F.Cu" "F.Mask" "F.Paste")
			(net "P5E_CPU0_P3_TX_C_DN<15>")
		)
		(pad "2" smd rect
			(at 0.2667 0)
			(size 0.3048 0.381)
			(layers "F.Cu" "F.Mask" "F.Paste")
			(net "P5E_CPU0_P3_TX_DN<15>")
		)
	)
	(footprint ""
		(layer "F.Cu")
		(at 345.467686 -23.8887 -90)
		(property "Reference" "R947"
			(at 0 0 270)
			(layer "F.SilkS")
			(hide yes)
			(effects
				(font
					(size 1.27 1.27)
				)
			)
		)
		(property "Value" ""
			(at 0 0 270)
			(layer "F.Fab")
			(effects
				(font
					(size 1.27 1.27)
				)
			)
		)
		(duplicate_pad_numbers_are_jumpers no)
		(fp_line
			(start -0.7874 0.4064)
			(end -0.7874 -0.4064)
			(stroke
				(width 0.1524)
				(type default)
			)
			(layer "F.SilkS")
		)
		(fp_line
			(start 0.7874 0.4064)
			(end -0.7874 0.4064)
			(stroke
				(width 0.1524)
				(type default)
			)
			(layer "F.SilkS")
		)
		(fp_line
			(start -0.7874 -0.4064)
			(end 0.7874 -0.4064)
			(stroke
				(width 0.1524)
				(type default)
			)
			(layer "F.SilkS")
		)
		(fp_line
			(start 0.7874 -0.4064)
			(end 0.7874 0.4064)
			(stroke
				(width 0.1524)
				(type default)
			)
			(layer "F.SilkS")
		)
		(fp_line
			(start -0.67945 0.3048)
			(end -0.67945 -0.305054)
			(stroke
				(width 0.1)
				(type default)
			)
			(layer "F.Fab")
		)
		(fp_line
			(start -0.12065 0.3048)
			(end -0.67945 0.3048)
			(stroke
				(width 0.1)
				(type default)
			)
			(layer "F.Fab")
		)
		(fp_line
			(start 0.120396 0.3048)
			(end 0.120396 0.2794)
			(stroke
				(width 0.1)
				(type default)
			)
			(layer "F.Fab")
		)
		(fp_line
			(start 0.67945 0.3048)
			(end 0.120396 0.3048)
			(stroke
				(width 0.1)
				(type default)
			)
			(layer "F.Fab")
		)
		(fp_line
			(start -0.12065 0.2794)
			(end -0.12065 0.3048)
			(stroke
				(width 0.1)
				(type default)
			)
			(layer "F.Fab")
		)
		(fp_line
			(start 0.120396 0.2794)
			(end -0.12065 0.2794)
			(stroke
				(width 0.1)
				(type default)
			)
			(layer "F.Fab")
		)
		(fp_line
			(start -0.12065 -0.2794)
			(end 0.12065 -0.2794)
			(stroke
				(width 0.1)
				(type default)
			)
			(layer "F.Fab")
		)
		(fp_line
			(start 0.12065 -0.2794)
			(end 0.12065 -0.3048)
			(stroke
				(width 0.1)
				(type default)
			)
			(layer "F.Fab")
		)
		(fp_line
			(start 0.12065 -0.3048)
			(end 0.67945 -0.3048)
			(stroke
				(width 0.1)
				(type default)
			)
			(layer "F.Fab")
		)
		(fp_line
			(start 0.67945 -0.3048)
			(end 0.67945 0.3048)
			(stroke
				(width 0.1)
				(type default)
			)
			(layer "F.Fab")
		)
		(fp_line
			(start -0.67945 -0.305054)
			(end -0.12065 -0.305054)
			(stroke
				(width 0.1)
				(type default)
			)
			(layer "F.Fab")
		)
		(fp_line
			(start -0.12065 -0.305054)
			(end -0.12065 -0.2794)
			(stroke
				(width 0.1)
				(type default)
			)
			(layer "F.Fab")
		)
		(pad "1" smd circle
			(at -0.40005 0 270)
			(size 0 0)
			(layers "F.Cu" "F.Mask" "F.Paste")
			(net "P3V3_AUX")
		)
		(pad "2" smd circle
			(at 0.40005 0 270)
			(size 0 0)
			(layers "F.Cu" "F.Mask" "F.Paste")
			(net "SMERR_LED")
		)
	)
	(footprint ""
		(layer "F.Cu")
		(at 310.75757 -22.185884 90)
		(property "Reference" "C63"
			(at 0 0 90)
			(layer "F.SilkS")
			(hide yes)
			(effects
				(font
					(size 1.27 1.27)
				)
			)
		)
		(property "Value" ""
			(at 0 0 90)
			(layer "F.Fab")
			(effects
				(font
					(size 1.27 1.27)
				)
			)
		)
		(duplicate_pad_numbers_are_jumpers no)
		(fp_line
			(start 0.7874 -0.4064)
			(end 0.7874 0.4064)
			(stroke
				(width 0.1524)
				(type default)
			)
			(layer "F.SilkS")
		)
		(fp_line
			(start -0.7874 -0.4064)
			(end 0.7874 -0.4064)
			(stroke
				(width 0.1524)
				(type default)
			)
			(layer "F.SilkS")
		)
		(fp_line
			(start 0.7874 0.4064)
			(end -0.7874 0.4064)
			(stroke
				(width 0.1524)
				(type default)
			)
			(layer "F.SilkS")
		)
		(fp_line
			(start -0.7874 0.4064)
			(end -0.7874 -0.4064)
			(stroke
				(width 0.1524)
				(type default)
			)
			(layer "F.SilkS")
		)
		(fp_line
			(start -0.12065 -0.305054)
			(end -0.12065 -0.2794)
			(stroke
				(width 0.1)
				(type default)
			)
			(layer "F.Fab")
		)
		(fp_line
			(start -0.67945 -0.305054)
			(end -0.12065 -0.305054)
			(stroke
				(width 0.1)
				(type default)
			)
			(layer "F.Fab")
		)
		(fp_line
			(start 0.67945 -0.3048)
			(end 0.67945 0.3048)
			(stroke
				(width 0.1)
				(type default)
			)
			(layer "F.Fab")
		)
		(fp_line
			(start 0.12065 -0.3048)
			(end 0.67945 -0.3048)
			(stroke
				(width 0.1)
				(type default)
			)
			(layer "F.Fab")
		)
		(fp_line
			(start 0.12065 -0.2794)
			(end 0.12065 -0.3048)
			(stroke
				(width 0.1)
				(type default)
			)
			(layer "F.Fab")
		)
		(fp_line
			(start -0.12065 -0.2794)
			(end 0.12065 -0.2794)
			(stroke
				(width 0.1)
				(type default)
			)
			(layer "F.Fab")
		)
		(fp_line
			(start 0.120396 0.2794)
			(end -0.12065 0.2794)
			(stroke
				(width 0.1)
				(type default)
			)
			(layer "F.Fab")
		)
		(fp_line
			(start -0.12065 0.2794)
			(end -0.12065 0.3048)
			(stroke
				(width 0.1)
				(type default)
			)
			(layer "F.Fab")
		)
		(fp_line
			(start 0.67945 0.3048)
			(end 0.120396 0.3048)
			(stroke
				(width 0.1)
				(type default)
			)
			(layer "F.Fab")
		)
		(fp_line
			(start 0.120396 0.3048)
			(end 0.120396 0.2794)
			(stroke
				(width 0.1)
				(type default)
			)
			(layer "F.Fab")
		)
		(fp_line
			(start -0.12065 0.3048)
			(end -0.67945 0.3048)
			(stroke
				(width 0.1)
				(type default)
			)
			(layer "F.Fab")
		)
		(fp_line
			(start -0.67945 0.3048)
			(end -0.67945 -0.305054)
			(stroke
				(width 0.1)
				(type default)
			)
			(layer "F.Fab")
		)
		(pad "1" smd circle
			(at -0.40005 0 90)
			(size 0 0)
			(layers "F.Cu" "F.Mask" "F.Paste")
			(net "UART_CPU0_SCM_LVC3_UART1_R_RX")
		)
		(pad "2" smd circle
			(at 0.40005 0 90)
			(size 0 0)
			(layers "F.Cu" "F.Mask" "F.Paste")
			(net "GND")
		)
	)
)
